(kicad_pcb
	(version 20260206)
	(generator "pcbnew")
	(generator_version "10.0")
	(general
		(thickness 1.6)
		(legacy_teardrops no)
	)
	(paper "A4")
	(title_block
		(title "01162023_DA0F0TEBIF0_F0T_Expander_BD_F_brd_V02_OCP.brd")
		(comment 1 "Grand Teton / footprints 2870-2876 of 9728")
	)
	(layers
		(0 "F.Cu" signal "TOP")
		(4 "In1.Cu" signal "GND")
		(6 "In2.Cu" signal "VCC")
		(8 "In3.Cu" signal "VCC1")
		(10 "In4.Cu" signal "GND1")
		(12 "In5.Cu" signal "IN1")
		(14 "In6.Cu" signal "GND2")
		(16 "In7.Cu" signal "IN2")
		(18 "In8.Cu" signal "GND3")
		(20 "In9.Cu" signal "IN3")
		(22 "In10.Cu" signal "GND4")
		(24 "In11.Cu" signal "IN4")
		(26 "In12.Cu" signal "GND5")
		(28 "In13.Cu" signal "IN5")
		(30 "In14.Cu" signal "GND6")
		(32 "In15.Cu" signal "IN6")
		(34 "In16.Cu" signal "GND7")
		(2 "B.Cu" signal "BOTTOM")
		(9 "F.Adhes" user "F.Adhesive")
		(11 "B.Adhes" user "B.Adhesive")
		(13 "F.Paste" user "Package Geometry/Pastemask Top")
		(15 "B.Paste" user "Package Geometry/Pastemask Bottom")
		(5 "F.SilkS" user "Ref Des/Silkscreen Top")
		(7 "B.SilkS" user "Ref Des/Silkscreen Bottom")
		(1 "F.Mask" user "Board Geometry/Soldermask Top")
		(3 "B.Mask" user "Board Geometry/Soldermask Bottom")
		(17 "Dwgs.User" user "User.Drawings")
		(19 "Cmts.User" user "User.Comments")
		(21 "Eco1.User" user "User.Eco1")
		(23 "Eco2.User" user "User.Eco2")
		(25 "Edge.Cuts" user "Board Geometry/Outline")
		(27 "Margin" user)
		(31 "F.CrtYd" user "Package Geometry/Place Bound Top")
		(29 "B.CrtYd" user "Package Geometry/Place Bound Bottom")
		(35 "F.Fab" user "Ref Des/Assembly Top")
		(33 "B.Fab" user "Ref Des/Assembly Bottom")
	)
	(footprint ""
		(layer "F.Cu")
		(at 413.293052 -343.952322 90)
		(property "Reference" "C2442"
			(at 0 0 90)
			(layer "F.SilkS")
			(hide yes)
			(effects
				(font
					(size 1.27 1.27)
				)
			)
		)
		(property "Value" ""
			(at 0 0 90)
			(layer "F.Fab")
			(effects
				(font
					(size 1.27 1.27)
				)
			)
		)
		(duplicate_pad_numbers_are_jumpers no)
		(fp_line
			(start 0.299974 -0.150114)
			(end 0.299974 0.150114)
			(stroke
				(width 0.1)
				(type default)
			)
			(layer "F.Fab")
		)
		(fp_line
			(start -0.299974 -0.150114)
			(end 0.299974 -0.150114)
			(stroke
				(width 0.1)
				(type default)
			)
			(layer "F.Fab")
		)
		(fp_line
			(start 0.299974 0.150114)
			(end -0.299974 0.150114)
			(stroke
				(width 0.1)
				(type default)
			)
			(layer "F.Fab")
		)
		(fp_line
			(start -0.299974 0.150114)
			(end -0.299974 -0.150114)
			(stroke
				(width 0.1)
				(type default)
			)
			(layer "F.Fab")
		)
		(pad "1" smd rect
			(at -0.2667 0 90)
			(size 0.3048 0.381)
			(layers "F.Cu" "F.Mask" "F.Paste")
			(net "P5E_PEX3_STN4_TX_DN<78>")
		)
		(pad "2" smd rect
			(at 0.2667 0 90)
			(size 0.3048 0.381)
			(layers "F.Cu" "F.Mask" "F.Paste")
			(net "P5E_PEX3_STN4_TX_C_DN<78>")
		)
	)
	(footprint ""
		(layer "F.Cu")
		(at 418.247068 -55.63489 90)
		(property "Reference" "PC892"
			(at 0 0 90)
			(layer "F.SilkS")
			(hide yes)
			(effects
				(font
					(size 1.27 1.27)
				)
			)
		)
		(property "Value" ""
			(at 0 0 90)
			(layer "F.Fab")
			(effects
				(font
					(size 1.27 1.27)
				)
			)
		)
		(duplicate_pad_numbers_are_jumpers no)
		(fp_line
			(start 1.524 -0.762)
			(end 1.524 0.762)
			(stroke
				(width 0.1524)
				(type default)
			)
			(layer "F.SilkS")
		)
		(fp_line
			(start -1.524 -0.762)
			(end 1.524 -0.762)
			(stroke
				(width 0.1524)
				(type default)
			)
			(layer "F.SilkS")
		)
		(fp_line
			(start 1.524 0.762)
			(end -1.524 0.762)
			(stroke
				(width 0.1524)
				(type default)
			)
			(layer "F.SilkS")
		)
		(fp_line
			(start -1.524 0.762)
			(end -1.524 -0.762)
			(stroke
				(width 0.1524)
				(type default)
			)
			(layer "F.SilkS")
		)
		(fp_line
			(start 1.1049 -0.724916)
			(end -1.1049 -0.724916)
			(stroke
				(width 0.1)
				(type default)
			)
			(layer "F.Fab")
		)
		(fp_line
			(start -1.1049 -0.724916)
			(end -1.1049 0.724916)
			(stroke
				(width 0.1)
				(type default)
			)
			(layer "F.Fab")
		)
		(fp_line
			(start 1.1049 0.724916)
			(end 1.1049 -0.724916)
			(stroke
				(width 0.1)
				(type default)
			)
			(layer "F.Fab")
		)
		(fp_line
			(start -1.1049 0.724916)
			(end 1.1049 0.724916)
			(stroke
				(width 0.1)
				(type default)
			)
			(layer "F.Fab")
		)
		(pad "1" smd rect
			(at -0.889 0 270)
			(size 1.016 1.27)
			(layers "F.Cu" "F.Mask" "F.Paste")
			(net "P12V_SSD14_R")
		)
		(pad "2" smd rect
			(at 0.889 0 270)
			(size 1.016 1.27)
			(layers "F.Cu" "F.Mask" "F.Paste")
			(net "GND")
		)
	)
	(footprint ""
		(layer "F.Cu")
		(at 149.315932 -386.66801 90)
		(property "Reference" "C4099"
			(at 0 0 90)
			(layer "F.SilkS")
			(hide yes)
			(effects
				(font
					(size 1.27 1.27)
				)
			)
		)
		(property "Value" ""
			(at 0 0 90)
			(layer "F.Fab")
			(effects
				(font
					(size 1.27 1.27)
				)
			)
		)
		(duplicate_pad_numbers_are_jumpers no)
		(fp_line
			(start 0.7874 -0.4064)
			(end 0.7874 0.4064)
			(stroke
				(width 0.1524)
				(type default)
			)
			(layer "F.SilkS")
		)
		(fp_line
			(start -0.7874 -0.4064)
			(end 0.7874 -0.4064)
			(stroke
				(width 0.1524)
				(type default)
			)
			(layer "F.SilkS")
		)
		(fp_line
			(start 0.7874 0.4064)
			(end -0.7874 0.4064)
			(stroke
				(width 0.1524)
				(type default)
			)
			(layer "F.SilkS")
		)
		(fp_line
			(start -0.7874 0.4064)
			(end -0.7874 -0.4064)
			(stroke
				(width 0.1524)
				(type default)
			)
			(layer "F.SilkS")
		)
		(fp_line
			(start -0.12065 -0.305054)
			(end -0.12065 -0.2794)
			(stroke
				(width 0.1)
				(type default)
			)
			(layer "F.Fab")
		)
		(fp_line
			(start -0.67945 -0.305054)
			(end -0.12065 -0.305054)
			(stroke
				(width 0.1)
				(type default)
			)
			(layer "F.Fab")
		)
		(fp_line
			(start 0.67945 -0.3048)
			(end 0.67945 0.3048)
			(stroke
				(width 0.1)
				(type default)
			)
			(layer "F.Fab")
		)
		(fp_line
			(start 0.12065 -0.3048)
			(end 0.67945 -0.3048)
			(stroke
				(width 0.1)
				(type default)
			)
			(layer "F.Fab")
		)
		(fp_line
			(start 0.12065 -0.2794)
			(end 0.12065 -0.3048)
			(stroke
				(width 0.1)
				(type default)
			)
			(layer "F.Fab")
		)
		(fp_line
			(start -0.12065 -0.2794)
			(end 0.12065 -0.2794)
			(stroke
				(width 0.1)
				(type default)
			)
			(layer "F.Fab")
		)
		(fp_line
			(start 0.120396 0.2794)
			(end -0.12065 0.2794)
			(stroke
				(width 0.1)
				(type default)
			)
			(layer "F.Fab")
		)
		(fp_line
			(start -0.12065 0.2794)
			(end -0.12065 0.3048)
			(stroke
				(width 0.1)
				(type default)
			)
			(layer "F.Fab")
		)
		(fp_line
			(start 0.67945 0.3048)
			(end 0.120396 0.3048)
			(stroke
				(width 0.1)
				(type default)
			)
			(layer "F.Fab")
		)
		(fp_line
			(start 0.120396 0.3048)
			(end 0.120396 0.2794)
			(stroke
				(width 0.1)
				(type default)
			)
			(layer "F.Fab")
		)
		(fp_line
			(start -0.12065 0.3048)
			(end -0.67945 0.3048)
			(stroke
				(width 0.1)
				(type default)
			)
			(layer "F.Fab")
		)
		(fp_line
			(start -0.67945 0.3048)
			(end -0.67945 -0.305054)
			(stroke
				(width 0.1)
				(type default)
			)
			(layer "F.Fab")
		)
		(pad "1" smd circle
			(at -0.40005 0 90)
			(size 0 0)
			(layers "F.Cu" "F.Mask" "F.Paste")
			(net "GND")
		)
		(pad "2" smd circle
			(at 0.40005 0 90)
			(size 0 0)
			(layers "F.Cu" "F.Mask" "F.Paste")
			(net "GPU_BASE_HMC_READY")
		)
	)
	(footprint ""
		(layer "F.Cu")
		(at 281.867864 -18.437098)
		(property "Reference" "R1694"
			(at 0 0 0)
			(layer "F.SilkS")
			(hide yes)
			(effects
				(font
					(size 1.27 1.27)
				)
			)
		)
		(property "Value" ""
			(at 0 0 0)
			(layer "F.Fab")
			(effects
				(font
					(size 1.27 1.27)
				)
			)
		)
		(duplicate_pad_numbers_are_jumpers no)
		(fp_line
			(start -0.7874 -0.4064)
			(end 0.7874 -0.4064)
			(stroke
				(width 0.1524)
				(type default)
			)
			(layer "F.SilkS")
		)
		(fp_line
			(start -0.7874 0.4064)
			(end -0.7874 -0.4064)
			(stroke
				(width 0.1524)
				(type default)
			)
			(layer "F.SilkS")
		)
		(fp_line
			(start 0.7874 -0.4064)
			(end 0.7874 0.4064)
			(stroke
				(width 0.1524)
				(type default)
			)
			(layer "F.SilkS")
		)
		(fp_line
			(start 0.7874 0.4064)
			(end -0.7874 0.4064)
			(stroke
				(width 0.1524)
				(type default)
			)
			(layer "F.SilkS")
		)
		(fp_line
			(start -0.67945 -0.305054)
			(end -0.12065 -0.305054)
			(stroke
				(width 0.1)
				(type default)
			)
			(layer "F.Fab")
		)
		(fp_line
			(start -0.67945 0.3048)
			(end -0.67945 -0.305054)
			(stroke
				(width 0.1)
				(type default)
			)
			(layer "F.Fab")
		)
		(fp_line
			(start -0.12065 -0.305054)
			(end -0.12065 -0.2794)
			(stroke
				(width 0.1)
				(type default)
			)
			(layer "F.Fab")
		)
		(fp_line
			(start -0.12065 -0.2794)
			(end 0.12065 -0.2794)
			(stroke
				(width 0.1)
				(type default)
			)
			(layer "F.Fab")
		)
		(fp_line
			(start -0.12065 0.2794)
			(end -0.12065 0.3048)
			(stroke
				(width 0.1)
				(type default)
			)
			(layer "F.Fab")
		)
		(fp_line
			(start -0.12065 0.3048)
			(end -0.67945 0.3048)
			(stroke
				(width 0.1)
				(type default)
			)
			(layer "F.Fab")
		)
		(fp_line
			(start 0.120396 0.2794)
			(end -0.12065 0.2794)
			(stroke
				(width 0.1)
				(type default)
			)
			(layer "F.Fab")
		)
		(fp_line
			(start 0.120396 0.3048)
			(end 0.120396 0.2794)
			(stroke
				(width 0.1)
				(type default)
			)
			(layer "F.Fab")
		)
		(fp_line
			(start 0.12065 -0.3048)
			(end 0.67945 -0.3048)
			(stroke
				(width 0.1)
				(type default)
			)
			(layer "F.Fab")
		)
		(fp_line
			(start 0.12065 -0.2794)
			(end 0.12065 -0.3048)
			(stroke
				(width 0.1)
				(type default)
			)
			(layer "F.Fab")
		)
		(fp_line
			(start 0.67945 -0.3048)
			(end 0.67945 0.3048)
			(stroke
				(width 0.1)
				(type default)
			)
			(layer "F.Fab")
		)
		(fp_line
			(start 0.67945 0.3048)
			(end 0.120396 0.3048)
			(stroke
				(width 0.1)
				(type default)
			)
			(layer "F.Fab")
		)
		(pad "1" smd circle
			(at -0.40005 0)
			(size 0 0)
			(layers "F.Cu" "F.Mask" "F.Paste")
			(net "SMB_ISO_SSD9_R_SCL")
		)
		(pad "2" smd circle
			(at 0.40005 0)
			(size 0 0)
			(layers "F.Cu" "F.Mask" "F.Paste")
			(net "SMB_ISO_SSD9_SCL")
		)
	)
	(footprint ""
		(layer "F.Cu")
		(at 255.17729 -77.279754 90)
		(property "Reference" "R1068"
			(at 0 0 90)
			(layer "F.SilkS")
			(hide yes)
			(effects
				(font
					(size 1.27 1.27)
				)
			)
		)
		(property "Value" ""
			(at 0 0 90)
			(layer "F.Fab")
			(effects
				(font
					(size 1.27 1.27)
				)
			)
		)
		(duplicate_pad_numbers_are_jumpers no)
		(fp_line
			(start 0.7874 -0.4064)
			(end 0.7874 0.4064)
			(stroke
				(width 0.1524)
				(type default)
			)
			(layer "F.SilkS")
		)
		(fp_line
			(start -0.7874 -0.4064)
			(end 0.7874 -0.4064)
			(stroke
				(width 0.1524)
				(type default)
			)
			(layer "F.SilkS")
		)
		(fp_line
			(start 0.7874 0.4064)
			(end -0.7874 0.4064)
			(stroke
				(width 0.1524)
				(type default)
			)
			(layer "F.SilkS")
		)
		(fp_line
			(start -0.7874 0.4064)
			(end -0.7874 -0.4064)
			(stroke
				(width 0.1524)
				(type default)
			)
			(layer "F.SilkS")
		)
		(fp_line
			(start -0.12065 -0.305054)
			(end -0.12065 -0.2794)
			(stroke
				(width 0.1)
				(type default)
			)
			(layer "F.Fab")
		)
		(fp_line
			(start -0.67945 -0.305054)
			(end -0.12065 -0.305054)
			(stroke
				(width 0.1)
				(type default)
			)
			(layer "F.Fab")
		)
		(fp_line
			(start 0.67945 -0.3048)
			(end 0.67945 0.3048)
			(stroke
				(width 0.1)
				(type default)
			)
			(layer "F.Fab")
		)
		(fp_line
			(start 0.12065 -0.3048)
			(end 0.67945 -0.3048)
			(stroke
				(width 0.1)
				(type default)
			)
			(layer "F.Fab")
		)
		(fp_line
			(start 0.12065 -0.2794)
			(end 0.12065 -0.3048)
			(stroke
				(width 0.1)
				(type default)
			)
			(layer "F.Fab")
		)
		(fp_line
			(start -0.12065 -0.2794)
			(end 0.12065 -0.2794)
			(stroke
				(width 0.1)
				(type default)
			)
			(layer "F.Fab")
		)
		(fp_line
			(start 0.120396 0.2794)
			(end -0.12065 0.2794)
			(stroke
				(width 0.1)
				(type default)
			)
			(layer "F.Fab")
		)
		(fp_line
			(start -0.12065 0.2794)
			(end -0.12065 0.3048)
			(stroke
				(width 0.1)
				(type default)
			)
			(layer "F.Fab")
		)
		(fp_line
			(start 0.67945 0.3048)
			(end 0.120396 0.3048)
			(stroke
				(width 0.1)
				(type default)
			)
			(layer "F.Fab")
		)
		(fp_line
			(start 0.120396 0.3048)
			(end 0.120396 0.2794)
			(stroke
				(width 0.1)
				(type default)
			)
			(layer "F.Fab")
		)
		(fp_line
			(start -0.12065 0.3048)
			(end -0.67945 0.3048)
			(stroke
				(width 0.1)
				(type default)
			)
			(layer "F.Fab")
		)
		(fp_line
			(start -0.67945 0.3048)
			(end -0.67945 -0.305054)
			(stroke
				(width 0.1)
				(type default)
			)
			(layer "F.Fab")
		)
		(pad "1" smd circle
			(at -0.40005 0 90)
			(size 0 0)
			(layers "F.Cu" "F.Mask" "F.Paste")
			(net "GND")
		)
		(pad "2" smd circle
			(at 0.40005 0 90)
			(size 0 0)
			(layers "F.Cu" "F.Mask" "F.Paste")
			(net "FM_CLK_CK440_SS_EN")
		)
	)
	(footprint ""
		(layer "F.Cu")
		(at 330.77531 -69.47916 180)
		(property "Reference" "PU113"
			(at -1.86436 4.02844 90)
			(unlocked yes)
			(layer "F.SilkS")
			(effects
				(font
					(size 0.7874 0.5842)
					(thickness 0.1524)
				)
			)
		)
		(property "Value" ""
			(at 0 0 180)
			(layer "F.Fab")
			(effects
				(font
					(size 1.27 1.27)
				)
			)
		)
		(duplicate_pad_numbers_are_jumpers no)
		(fp_line
			(start 1.239774 1.495298)
			(end -1.239774 1.495298)
			(stroke
				(width 0.1524)
				(type default)
			)
			(layer "F.SilkS")
		)
		(fp_line
			(start 1.239774 -1.495298)
			(end 1.239774 1.495298)
			(stroke
				(width 0.1524)
				(type default)
			)
			(layer "F.SilkS")
		)
		(fp_line
			(start -1.239774 1.495298)
			(end -1.239774 -1.495298)
			(stroke
				(width 0.1524)
				(type default)
			)
			(layer "F.SilkS")
		)
		(fp_line
			(start -1.239774 -1.495298)
			(end 1.239774 -1.495298)
			(stroke
				(width 0.1524)
				(type default)
			)
			(layer "F.SilkS")
		)
		(fp_poly
			(pts
				(xy -1.764792 -1.332738) (xy -2.483104 -0.614172) (xy -1.405382 -0.255016)
			)
			(stroke
				(width 0)
				(type default)
			)
			(fill yes)
			(layer "F.SilkS")
		)
		(fp_line
			(start 0.8001 1.050036)
			(end -0.8001 1.050036)
			(stroke
				(width 0.1)
				(type default)
			)
			(layer "F.Fab")
		)
		(fp_line
			(start 0.8001 -1.050036)
			(end 0.8001 1.050036)
			(stroke
				(width 0.1)
				(type default)
			)
			(layer "F.Fab")
		)
		(fp_line
			(start -0.8001 1.050036)
			(end -0.8001 -1.050036)
			(stroke
				(width 0.1)
				(type default)
			)
			(layer "F.Fab")
		)
		(fp_line
			(start -0.8001 -1.050036)
			(end 0.8001 -1.050036)
			(stroke
				(width 0.1)
				(type default)
			)
			(layer "F.Fab")
		)
		(fp_poly
			(pts
				(xy -2.458974 -0.508) (xy -2.458974 0.508) (xy -1.442974 0)
			)
			(stroke
				(width 0)
				(type default)
			)
			(fill yes)
			(layer "F.Fab")
		)
		(pad "1_2" smd circle
			(at -0.374904 0 270)
			(size 0 0)
			(layers "F.Cu" "F.Mask" "F.Paste")
			(net "P12V_AUX")
		)
		(pad "3" smd rect
			(at -0.499872 0.999998 180)
			(size 0.254 0.7112)
			(layers "F.Cu" "F.Mask" "F.Paste")
			(net "GND")
		)
		(pad "4" smd rect
			(at 0 0.999998 180)
			(size 0.254 0.7112)
			(layers "F.Cu" "F.Mask" "F.Paste")
			(net "P12V_SSD11_CO_ILIMIT")
		)
		(pad "5" smd rect
			(at 0.499872 0.999998 180)
			(size 0.254 0.7112)
			(layers "F.Cu" "F.Mask" "F.Paste")
			(net "P12V_SSD11_CO_MODE")
		)
		(pad "6_7" smd circle
			(at 0.374904 0 90)
			(size 0 0)
			(layers "F.Cu" "F.Mask" "F.Paste")
			(net "P12V_SSD11_R")
		)
		(pad "8" smd rect
			(at 0.499872 -0.999998 180)
			(size 0.254 0.7112)
			(layers "F.Cu" "F.Mask" "F.Paste")
			(net "P12V_SSD11_CO_GATE")
		)
		(pad "9" smd rect
			(at 0 -0.999998 180)
			(size 0.254 0.7112)
			(layers "F.Cu" "F.Mask" "F.Paste")
			(net "P12V_SSD11_CO_EN")
		)
		(pad "10" smd rect
			(at -0.499872 -0.999998 180)
			(size 0.254 0.7112)
			(layers "F.Cu" "F.Mask" "F.Paste")
			(net "P12V_SSD11_CO_DV_DT")
		)
	)
	(footprint ""
		(layer "F.Cu")
		(at 462.465674 -276.64283)
		(property "Reference" "R807"
			(at 0 0 0)
			(layer "F.SilkS")
			(hide yes)
			(effects
				(font
					(size 1.27 1.27)
				)
			)
		)
		(property "Value" ""
			(at 0 0 0)
			(layer "F.Fab")
			(effects
				(font
					(size 1.27 1.27)
				)
			)
		)
		(duplicate_pad_numbers_are_jumpers no)
		(fp_line
			(start -0.7874 -0.4064)
			(end 0.7874 -0.4064)
			(stroke
				(width 0.1524)
				(type default)
			)
			(layer "F.SilkS")
		)
		(fp_line
			(start -0.7874 0.4064)
			(end -0.7874 -0.4064)
			(stroke
				(width 0.1524)
				(type default)
			)
			(layer "F.SilkS")
		)
		(fp_line
			(start 0.7874 -0.4064)
			(end 0.7874 0.4064)
			(stroke
				(width 0.1524)
				(type default)
			)
			(layer "F.SilkS")
		)
		(fp_line
			(start 0.7874 0.4064)
			(end -0.7874 0.4064)
			(stroke
				(width 0.1524)
				(type default)
			)
			(layer "F.SilkS")
		)
		(fp_line
			(start -0.67945 -0.305054)
			(end -0.12065 -0.305054)
			(stroke
				(width 0.1)
				(type default)
			)
			(layer "F.Fab")
		)
		(fp_line
			(start -0.67945 0.3048)
			(end -0.67945 -0.305054)
			(stroke
				(width 0.1)
				(type default)
			)
			(layer "F.Fab")
		)
		(fp_line
			(start -0.12065 -0.305054)
			(end -0.12065 -0.2794)
			(stroke
				(width 0.1)
				(type default)
			)
			(layer "F.Fab")
		)
		(fp_line
			(start -0.12065 -0.2794)
			(end 0.12065 -0.2794)
			(stroke
				(width 0.1)
				(type default)
			)
			(layer "F.Fab")
		)
		(fp_line
			(start -0.12065 0.2794)
			(end -0.12065 0.3048)
			(stroke
				(width 0.1)
				(type default)
			)
			(layer "F.Fab")
		)
		(fp_line
			(start -0.12065 0.3048)
			(end -0.67945 0.3048)
			(stroke
				(width 0.1)
				(type default)
			)
			(layer "F.Fab")
		)
		(fp_line
			(start 0.120396 0.2794)
			(end -0.12065 0.2794)
			(stroke
				(width 0.1)
				(type default)
			)
			(layer "F.Fab")
		)
		(fp_line
			(start 0.120396 0.3048)
			(end 0.120396 0.2794)
			(stroke
				(width 0.1)
				(type default)
			)
			(layer "F.Fab")
		)
		(fp_line
			(start 0.12065 -0.3048)
			(end 0.67945 -0.3048)
			(stroke
				(width 0.1)
				(type default)
			)
			(layer "F.Fab")
		)
		(fp_line
			(start 0.12065 -0.2794)
			(end 0.12065 -0.3048)
			(stroke
				(width 0.1)
				(type default)
			)
			(layer "F.Fab")
		)
		(fp_line
			(start 0.67945 -0.3048)
			(end 0.67945 0.3048)
			(stroke
				(width 0.1)
				(type default)
			)
			(layer "F.Fab")
		)
		(fp_line
			(start 0.67945 0.3048)
			(end 0.120396 0.3048)
			(stroke
				(width 0.1)
				(type default)
			)
			(layer "F.Fab")
		)
		(pad "1" smd circle
			(at -0.40005 0)
			(size 0 0)
			(layers "F.Cu" "F.Mask" "F.Paste")
			(net "PEX3_P1V25_ADC_A0")
		)
		(pad "2" smd circle
			(at 0.40005 0)
			(size 0 0)
			(layers "F.Cu" "F.Mask" "F.Paste")
			(net "GND")
		)
	)
)
